# BASEBOARD_FAB2 (Tioga Pass) — schematic netlist excerpt (pin names and nets, part order shuffled) for the footprints in the layout excerpt that follows; sources: Cadence DE-HDL packaged netlist, KiCad conversion of Wiwynn_Tioga_Pass_MB.brd

R1L37  RES  301.0 1% CHIP  pkg 0402  page 177 : A = P5V_STBY ; B = LED_P5V_STBY
CT14  CAP  1000PF 50V 10% X7R  pkg 0402LF  page 209 : A = VR_PVCCIN_CPU1_PHASE5 ; B = VR_PVCCIN_CPU1_PHASE5_RC
R1G20  RES  120.0 1% CHIP  pkg 0603  page 225 : A = PVDDQ_GHJ ; B = GND

(kicad_pcb
	(version 20260206)
	(generator "pcbnew")
	(generator_version "10.0")
	(general
		(thickness 1.6)
		(legacy_teardrops no)
	)
	(paper "A4")
	(title_block
		(title "Wiwynn_Tioga_Pass_MB.brd")
		(comment 1 "Tioga Pass / footprints 511-513 of 4770")
	)
	(layers
		(0 "F.Cu" signal "TOP")
		(4 "In1.Cu" signal "L2GND")
		(6 "In2.Cu" signal "L3")
		(8 "In3.Cu" signal "L4GND")
		(10 "In4.Cu" signal "L5")
		(12 "In5.Cu" signal "L6GND")
		(14 "In6.Cu" signal "L7VCC")
		(16 "In7.Cu" signal "L8VCC")
		(18 "In8.Cu" signal "L9GND")
		(20 "In9.Cu" signal "L10")
		(22 "In10.Cu" signal "L11GND")
		(24 "In11.Cu" signal "L12")
		(26 "In12.Cu" signal "L13GND")
		(2 "B.Cu" signal "BOTTOM")
		(9 "F.Adhes" user "F.Adhesive")
		(11 "B.Adhes" user "B.Adhesive")
		(13 "F.Paste" user "Package Geometry/Pastemask Top")
		(15 "B.Paste" user "Package Geometry/Pastemask Bottom")
		(5 "F.SilkS" user "Ref Des/Silkscreen Top")
		(7 "B.SilkS" user "Ref Des/Silkscreen Bottom")
		(1 "F.Mask" user "Board Geometry/Soldermask Top")
		(3 "B.Mask" user "Board Geometry/Soldermask Bottom")
		(17 "Dwgs.User" user "User.Drawings")
		(19 "Cmts.User" user "User.Comments")
		(21 "Eco1.User" user "User.Eco1")
		(23 "Eco2.User" user "User.Eco2")
		(25 "Edge.Cuts" user "Board Geometry/Outline")
		(27 "Margin" user)
		(31 "F.CrtYd" user "Package Geometry/Place Bound Top")
		(29 "B.CrtYd" user "Package Geometry/Place Bound Bottom")
		(35 "F.Fab" user "Ref Des/Assembly Top")
		(33 "B.Fab" user "Ref Des/Assembly Bottom")
	)
	(footprint ""
		(layer "F.Cu")
		(at 487.995976 -137.2616 -90)
		(property "Reference" "R1L37"
			(at 0 0 270)
			(layer "F.SilkS")
			(hide yes)
			(effects
				(font
					(size 1.27 1.27)
				)
			)
		)
		(property "Value" ""
			(at 0 0 270)
			(layer "F.Fab")
			(effects
				(font
					(size 1.27 1.27)
				)
			)
		)
		(duplicate_pad_numbers_are_jumpers no)
		(fp_poly
			(pts
				(xy -0.2794 -0.1016) (xy 0.2794 -0.1016) (xy 0.2794 0.9906) (xy -0.2794 0.9906)
			)
			(stroke
				(width 0)
				(type default)
			)
			(fill no)
			(layer "F.CrtYd")
		)
		(fp_line
			(start -0.2794 0.9906)
			(end 0.2794 0.9906)
			(stroke
				(width 0.1)
				(type default)
			)
			(layer "F.Fab")
		)
		(fp_line
			(start 0.2794 0.9906)
			(end 0.2794 -0.1016)
			(stroke
				(width 0.1)
				(type default)
			)
			(layer "F.Fab")
		)
		(fp_line
			(start -0.2794 -0.1016)
			(end -0.2794 0.9906)
			(stroke
				(width 0.1)
				(type default)
			)
			(layer "F.Fab")
		)
		(fp_line
			(start 0.2794 -0.1016)
			(end -0.2794 -0.1016)
			(stroke
				(width 0.1)
				(type default)
			)
			(layer "F.Fab")
		)
		(pad "1" smd rect
			(at 0 0 270)
			(size 0.508 0.508)
			(layers "F.Cu" "F.Mask" "F.Paste")
			(net "P5V_STBY")
		)
		(pad "2" smd rect
			(at 0 0.889 270)
			(size 0.508 0.508)
			(layers "F.Cu" "F.Mask" "F.Paste")
			(net "LED_P5V_STBY")
		)
		(zone
			(layer "F.Cu")
			(hatch none 0.5)
			(connect_pads
				(clearance 0)
			)
			(min_thickness 0.25)
			(keepout
				(tracks not_allowed)
				(vias allowed)
				(pads allowed)
				(copperpour not_allowed)
				(footprints allowed)
			)
			(placement
				(enabled no)
				(sheetname "")
			)
			(fill
				(thermal_gap 0.5)
				(thermal_bridge_width 0.5)
				(island_removal_mode 0)
			)
			(polygon
				(pts
					(xy 487.360976 -137.5156) (xy 487.360976 -137.0076) (xy 487.741976 -137.0076) (xy 487.741976 -137.5156)
				)
			)
		)
		(zone
			(layer "F.Cu")
			(hatch none 0.5)
			(connect_pads
				(clearance 0)
			)
			(min_thickness 0.25)
			(keepout
				(tracks allowed)
				(vias not_allowed)
				(pads allowed)
				(copperpour not_allowed)
				(footprints allowed)
			)
			(placement
				(enabled no)
				(sheetname "")
			)
			(fill
				(thermal_gap 0.5)
				(thermal_bridge_width 0.5)
				(island_removal_mode 0)
			)
			(polygon
				(pts
					(xy 487.741976 -137.5156) (xy 487.741976 -137.0076) (xy 487.360976 -137.0076) (xy 487.360976 -137.5156)
				)
			)
		)
	)
	(footprint ""
		(layer "F.Cu")
		(at 19.088608 -1.07696 -90)
		(property "Reference" "R1G20"
			(at 0 0 270)
			(layer "F.SilkS")
			(hide yes)
			(effects
				(font
					(size 1.27 1.27)
				)
			)
		)
		(property "Value" ""
			(at 0 0 270)
			(layer "F.Fab")
			(effects
				(font
					(size 1.27 1.27)
				)
			)
		)
		(duplicate_pad_numbers_are_jumpers no)
		(fp_rect
			(start 0.4953 1.6002)
			(end -0.4953 -0.2032)
			(stroke
				(width 0)
				(type default)
			)
			(fill no)
			(layer "F.CrtYd")
		)
		(fp_line
			(start -0.4953 1.6002)
			(end -0.4953 -0.2032)
			(stroke
				(width 0.1)
				(type default)
			)
			(layer "F.Fab")
		)
		(fp_line
			(start 0.4953 1.6002)
			(end -0.4953 1.6002)
			(stroke
				(width 0.1)
				(type default)
			)
			(layer "F.Fab")
		)
		(fp_line
			(start -0.4953 -0.2032)
			(end 0.4953 -0.2032)
			(stroke
				(width 0.1)
				(type default)
			)
			(layer "F.Fab")
		)
		(fp_line
			(start 0.4953 -0.2032)
			(end 0.4953 1.6002)
			(stroke
				(width 0.1)
				(type default)
			)
			(layer "F.Fab")
		)
		(pad "1" smd rect
			(at 0 0 270)
			(size 0.762 0.889)
			(layers "F.Cu" "F.Mask" "F.Paste")
			(net "PVDDQ_GHJ")
		)
		(pad "2" smd rect
			(at 0 1.397 270)
			(size 0.762 0.889)
			(layers "F.Cu" "F.Mask" "F.Paste")
			(net "GND")
		)
		(zone
			(layer "F.Cu")
			(hatch none 0.5)
			(connect_pads
				(clearance 0)
			)
			(min_thickness 0.25)
			(keepout
				(tracks not_allowed)
				(vias allowed)
				(pads allowed)
				(copperpour not_allowed)
				(footprints allowed)
			)
			(placement
				(enabled no)
				(sheetname "")
			)
			(fill
				(thermal_gap 0.5)
				(thermal_bridge_width 0.5)
				(island_removal_mode 0)
			)
			(polygon
				(pts
					(xy 18.136108 -0.69596) (xy 18.644108 -0.69596) (xy 18.644108 -1.45796) (xy 18.136108 -1.45796)
				)
			)
		)
		(zone
			(layer "F.Cu")
			(hatch none 0.5)
			(connect_pads
				(clearance 0)
			)
			(min_thickness 0.25)
			(keepout
				(tracks allowed)
				(vias not_allowed)
				(pads allowed)
				(copperpour not_allowed)
				(footprints allowed)
			)
			(placement
				(enabled no)
				(sheetname "")
			)
			(fill
				(thermal_gap 0.5)
				(thermal_bridge_width 0.5)
				(island_removal_mode 0)
			)
			(polygon
				(pts
					(xy 18.136108 -0.69596) (xy 18.644108 -0.69596) (xy 18.644108 -1.45796) (xy 18.136108 -1.45796)
				)
			)
		)
	)
	(footprint ""
		(layer "F.Cu")
		(at 38.965886 -85.6996 -90)
		(property "Reference" "CT14"
			(at -0.8382 -0.67818 270)
			(unlocked yes)
			(layer "F.SilkS")
			(effects
				(font
					(size 0.4064 0.254)
					(thickness 0.1524)
				)
				(justify left)
			)
		)
		(property "Value" ""
			(at 0 0 270)
			(layer "F.Fab")
			(effects
				(font
					(size 1.27 1.27)
				)
			)
		)
		(duplicate_pad_numbers_are_jumpers no)
		(fp_poly
			(pts
				(xy 0.3048 -0.1016) (xy 0.3048 0.9906) (xy -0.3048 0.9906) (xy -0.3048 -0.1016)
			)
			(stroke
				(width 0)
				(type default)
			)
			(fill no)
			(layer "F.CrtYd")
		)
		(fp_line
			(start -0.3048 0.9906)
			(end 0.3048 0.9906)
			(stroke
				(width 0.1)
				(type default)
			)
			(layer "F.Fab")
		)
		(fp_line
			(start 0.3048 0.9906)
			(end 0.3048 -0.1016)
			(stroke
				(width 0.1)
				(type default)
			)
			(layer "F.Fab")
		)
		(fp_line
			(start -0.3048 -0.1016)
			(end -0.3048 0.9906)
			(stroke
				(width 0.1)
				(type default)
			)
			(layer "F.Fab")
		)
		(fp_line
			(start 0.3048 -0.1016)
			(end -0.3048 -0.1016)
			(stroke
				(width 0.1)
				(type default)
			)
			(layer "F.Fab")
		)
		(pad "1" smd rect
			(at 0 0 270)
			(size 0.508 0.508)
			(layers "F.Cu" "F.Mask" "F.Paste")
			(net "VR_PVCCIN_CPU1_PHASE5")
		)
		(pad "2" smd rect
			(at 0 0.889 270)
			(size 0.508 0.508)
			(layers "F.Cu" "F.Mask" "F.Paste")
			(net "VR_PVCCIN_CPU1_PHASE5_RC")
		)
		(zone
			(layer "F.Cu")
			(hatch none 0.5)
			(connect_pads
				(clearance 0)
			)
			(min_thickness 0.25)
			(keepout
				(tracks not_allowed)
				(vias allowed)
				(pads allowed)
				(copperpour not_allowed)
				(footprints allowed)
			)
			(placement
				(enabled no)
				(sheetname "")
			)
			(fill
				(thermal_gap 0.5)
				(thermal_bridge_width 0.5)
				(island_removal_mode 0)
			)
			(polygon
				(pts
					(xy 38.330886 -85.9536) (xy 38.330886 -85.4456) (xy 38.711886 -85.4456) (xy 38.711886 -85.9536)
				)
			)
		)
		(zone
			(layer "F.Cu")
			(hatch none 0.5)
			(connect_pads
				(clearance 0)
			)
			(min_thickness 0.25)
			(keepout
				(tracks allowed)
				(vias not_allowed)
				(pads allowed)
				(copperpour not_allowed)
				(footprints allowed)
			)
			(placement
				(enabled no)
				(sheetname "")
			)
			(fill
				(thermal_gap 0.5)
				(thermal_bridge_width 0.5)
				(island_removal_mode 0)
			)
			(polygon
				(pts
					(xy 38.711886 -85.9536) (xy 38.711886 -85.4456) (xy 38.330886 -85.4456) (xy 38.330886 -85.9536)
				)
			)
		)
	)
)
